# T6G (Grand Teton) — schematic netlist excerpt (pin names and nets, part order shuffled) for the footprints in the layout excerpt that follows; sources: Cadence DE-HDL packaged netlist, KiCad conversion of 04192023_DAF0TMB3IC0_F0TG_MB_C_brd_V02_OCP.brd

C2215  Q_CAP  22UF 4V 20% X6S  pkg C0402  page 69 : A = PVDDCR_CPU1_P0 ; B = GND
R3941  Q_RES  0 5% CHIP  pkg 0402LF  page 257 : A = P12V_E1S_0_ISENSE_MAM_TIC ; B = P12V_E1S_0_ISENSE_TIC

(kicad_pcb
	(version 20260206)
	(generator "pcbnew")
	(generator_version "10.0")
	(general
		(thickness 1.6)
		(legacy_teardrops no)
	)
	(paper "A4")
	(title_block
		(title "04192023_DAF0TMB3IC0_F0TG_MB_C_brd_V02_OCP.brd")
		(comment 1 "Grand Teton / footprints 5452-5453 of 8354")
	)
	(layers
		(0 "F.Cu" signal "TOP")
		(4 "In1.Cu" signal "GND")
		(6 "In2.Cu" signal "IN1")
		(8 "In3.Cu" signal "GND1")
		(10 "In4.Cu" signal "IN2")
		(12 "In5.Cu" signal "GND2")
		(14 "In6.Cu" signal "IN3")
		(16 "In7.Cu" signal "GND3")
		(18 "In8.Cu" signal "VCC")
		(20 "In9.Cu" signal "VCC1")
		(22 "In10.Cu" signal "GND4")
		(24 "In11.Cu" signal "IN4")
		(26 "In12.Cu" signal "GND5")
		(28 "In13.Cu" signal "IN5")
		(30 "In14.Cu" signal "GND6")
		(32 "In15.Cu" signal "IN6")
		(34 "In16.Cu" signal "GND7")
		(2 "B.Cu" signal "BOTTOM")
		(9 "F.Adhes" user "F.Adhesive")
		(11 "B.Adhes" user "B.Adhesive")
		(13 "F.Paste" user "Package Geometry/Pastemask Top")
		(15 "B.Paste" user "Package Geometry/Pastemask Bottom")
		(5 "F.SilkS" user "Ref Des/Silkscreen Top")
		(7 "B.SilkS" user "Ref Des/Silkscreen Bottom")
		(1 "F.Mask" user "Board Geometry/Soldermask Top")
		(3 "B.Mask" user "Board Geometry/Soldermask Bottom")
		(17 "Dwgs.User" user "User.Drawings")
		(19 "Cmts.User" user "User.Comments")
		(21 "Eco1.User" user "User.Eco1")
		(23 "Eco2.User" user "User.Eco2")
		(25 "Edge.Cuts" user "Board Geometry/Outline")
		(27 "Margin" user)
		(31 "F.CrtYd" user "Package Geometry/Place Bound Top")
		(29 "B.CrtYd" user "Package Geometry/Place Bound Bottom")
		(35 "F.Fab" user "Ref Des/Assembly Top")
		(33 "B.Fab" user "Ref Des/Assembly Bottom")
	)
	(footprint ""
		(layer "B.Cu")
		(at 370.376958 -272.284952)
		(property "Reference" "C2215"
			(at 0 0 0)
			(layer "B.SilkS")
			(hide yes)
			(effects
				(font
					(size 1.27 1.27)
				)
				(justify mirror)
			)
		)
		(property "Value" ""
			(at 0 0 0)
			(layer "B.Fab")
			(effects
				(font
					(size 1.27 1.27)
				)
				(justify mirror)
			)
		)
		(duplicate_pad_numbers_are_jumpers no)
		(fp_line
			(start -0.7874 -0.4064)
			(end -0.7874 0.4064)
			(stroke
				(width 0.1524)
				(type default)
			)
			(layer "B.SilkS")
		)
		(fp_line
			(start -0.7874 0.4064)
			(end 0.7874 0.4064)
			(stroke
				(width 0.1524)
				(type default)
			)
			(layer "B.SilkS")
		)
		(fp_line
			(start 0.7874 -0.4064)
			(end -0.7874 -0.4064)
			(stroke
				(width 0.1524)
				(type default)
			)
			(layer "B.SilkS")
		)
		(fp_line
			(start 0.7874 0.4064)
			(end 0.7874 -0.4064)
			(stroke
				(width 0.1524)
				(type default)
			)
			(layer "B.SilkS")
		)
		(fp_line
			(start -0.67945 -0.3048)
			(end -0.67945 0.3048)
			(stroke
				(width 0.1)
				(type default)
			)
			(layer "B.Fab")
		)
		(fp_line
			(start -0.67945 0.3048)
			(end -0.120396 0.3048)
			(stroke
				(width 0.1)
				(type default)
			)
			(layer "B.Fab")
		)
		(fp_line
			(start -0.12065 -0.3048)
			(end -0.67945 -0.3048)
			(stroke
				(width 0.1)
				(type default)
			)
			(layer "B.Fab")
		)
		(fp_line
			(start -0.12065 -0.2794)
			(end -0.12065 -0.3048)
			(stroke
				(width 0.1)
				(type default)
			)
			(layer "B.Fab")
		)
		(fp_line
			(start -0.120396 0.2794)
			(end 0.12065 0.2794)
			(stroke
				(width 0.1)
				(type default)
			)
			(layer "B.Fab")
		)
		(fp_line
			(start -0.120396 0.3048)
			(end -0.120396 0.2794)
			(stroke
				(width 0.1)
				(type default)
			)
			(layer "B.Fab")
		)
		(fp_line
			(start 0.12065 -0.305054)
			(end 0.12065 -0.2794)
			(stroke
				(width 0.1)
				(type default)
			)
			(layer "B.Fab")
		)
		(fp_line
			(start 0.12065 -0.2794)
			(end -0.12065 -0.2794)
			(stroke
				(width 0.1)
				(type default)
			)
			(layer "B.Fab")
		)
		(fp_line
			(start 0.12065 0.2794)
			(end 0.12065 0.3048)
			(stroke
				(width 0.1)
				(type default)
			)
			(layer "B.Fab")
		)
		(fp_line
			(start 0.12065 0.3048)
			(end 0.67945 0.3048)
			(stroke
				(width 0.1)
				(type default)
			)
			(layer "B.Fab")
		)
		(fp_line
			(start 0.67945 -0.305054)
			(end 0.12065 -0.305054)
			(stroke
				(width 0.1)
				(type default)
			)
			(layer "B.Fab")
		)
		(fp_line
			(start 0.67945 0.3048)
			(end 0.67945 -0.305054)
			(stroke
				(width 0.1)
				(type default)
			)
			(layer "B.Fab")
		)
		(pad "1" smd circle
			(at 0.40005 0 180)
			(size 0 0)
			(layers "B.Cu" "B.Mask" "B.Paste")
			(net "PVDDCR_CPU1_P0")
		)
		(pad "2" smd circle
			(at -0.40005 0 180)
			(size 0 0)
			(layers "B.Cu" "B.Mask" "B.Paste")
			(net "GND")
		)
	)
	(footprint ""
		(layer "B.Cu")
		(at 315.585094 -40.33774 -90)
		(property "Reference" "R3941"
			(at 0 0 90)
			(layer "B.SilkS")
			(hide yes)
			(effects
				(font
					(size 1.27 1.27)
				)
				(justify mirror)
			)
		)
		(property "Value" ""
			(at 0 0 90)
			(layer "B.Fab")
			(effects
				(font
					(size 1.27 1.27)
				)
				(justify mirror)
			)
		)
		(duplicate_pad_numbers_are_jumpers no)
		(fp_line
			(start -0.7874 0.4064)
			(end 0.7874 0.4064)
			(stroke
				(width 0.1524)
				(type default)
			)
			(layer "B.SilkS")
		)
		(fp_line
			(start 0.7874 0.4064)
			(end 0.7874 -0.4064)
			(stroke
				(width 0.1524)
				(type default)
			)
			(layer "B.SilkS")
		)
		(fp_line
			(start -0.7874 -0.4064)
			(end -0.7874 0.4064)
			(stroke
				(width 0.1524)
				(type default)
			)
			(layer "B.SilkS")
		)
		(fp_line
			(start 0.7874 -0.4064)
			(end -0.7874 -0.4064)
			(stroke
				(width 0.1524)
				(type default)
			)
			(layer "B.SilkS")
		)
		(fp_line
			(start -0.67945 0.3048)
			(end -0.120396 0.3048)
			(stroke
				(width 0.1)
				(type default)
			)
			(layer "B.Fab")
		)
		(fp_line
			(start -0.120396 0.3048)
			(end -0.120396 0.2794)
			(stroke
				(width 0.1)
				(type default)
			)
			(layer "B.Fab")
		)
		(fp_line
			(start 0.12065 0.3048)
			(end 0.67945 0.3048)
			(stroke
				(width 0.1)
				(type default)
			)
			(layer "B.Fab")
		)
		(fp_line
			(start 0.67945 0.3048)
			(end 0.67945 -0.305054)
			(stroke
				(width 0.1)
				(type default)
			)
			(layer "B.Fab")
		)
		(fp_line
			(start -0.120396 0.2794)
			(end 0.12065 0.2794)
			(stroke
				(width 0.1)
				(type default)
			)
			(layer "B.Fab")
		)
		(fp_line
			(start 0.12065 0.2794)
			(end 0.12065 0.3048)
			(stroke
				(width 0.1)
				(type default)
			)
			(layer "B.Fab")
		)
		(fp_line
			(start -0.12065 -0.2794)
			(end -0.12065 -0.3048)
			(stroke
				(width 0.1)
				(type default)
			)
			(layer "B.Fab")
		)
		(fp_line
			(start 0.12065 -0.2794)
			(end -0.12065 -0.2794)
			(stroke
				(width 0.1)
				(type default)
			)
			(layer "B.Fab")
		)
		(fp_line
			(start -0.67945 -0.3048)
			(end -0.67945 0.3048)
			(stroke
				(width 0.1)
				(type default)
			)
			(layer "B.Fab")
		)
		(fp_line
			(start -0.12065 -0.3048)
			(end -0.67945 -0.3048)
			(stroke
				(width 0.1)
				(type default)
			)
			(layer "B.Fab")
		)
		(fp_line
			(start 0.12065 -0.305054)
			(end 0.12065 -0.2794)
			(stroke
				(width 0.1)
				(type default)
			)
			(layer "B.Fab")
		)
		(fp_line
			(start 0.67945 -0.305054)
			(end 0.12065 -0.305054)
			(stroke
				(width 0.1)
				(type default)
			)
			(layer "B.Fab")
		)
		(pad "1" smd rect
			(at 0.40005 0 270)
			(size 0.4572 0.508)
			(layers "B.Cu" "B.Mask" "B.Paste")
			(net "P12V_E1S_0_ISENSE_MAM_TIC")
		)
		(pad "2" smd rect
			(at -0.40005 0 270)
			(size 0.4572 0.508)
			(layers "B.Cu" "B.Mask" "B.Paste")
			(net "P12V_E1S_0_ISENSE_TIC")
		)
	)
)
